(kicad_pcb
	(version 20260206)
	(generator "pcbnew")
	(generator_version "10.0")
	(general
		(thickness 1.6)
		(legacy_teardrops no)
	)
	(paper "A4")
	(title_block
		(title "03242023_DA0F0TMBIJ0_F0T_Motherboard_J_brd_V01_OCP.brd")
		(comment 1 "Grand Teton / footprints 1866-1872 of 6105")
	)
	(layers
		(0 "F.Cu" signal "TOP")
		(4 "In1.Cu" signal "GND")
		(6 "In2.Cu" signal "IN1")
		(8 "In3.Cu" signal "GND1")
		(10 "In4.Cu" signal "IN2")
		(12 "In5.Cu" signal "GND2")
		(14 "In6.Cu" signal "IN3")
		(16 "In7.Cu" signal "GND3")
		(18 "In8.Cu" signal "VCC")
		(20 "In9.Cu" signal "VCC1")
		(22 "In10.Cu" signal "GND4")
		(24 "In11.Cu" signal "IN4")
		(26 "In12.Cu" signal "GND5")
		(28 "In13.Cu" signal "IN5")
		(30 "In14.Cu" signal "GND6")
		(32 "In15.Cu" signal "IN6")
		(34 "In16.Cu" signal "GND7")
		(2 "B.Cu" signal "BOTTOM")
		(9 "F.Adhes" user "F.Adhesive")
		(11 "B.Adhes" user "B.Adhesive")
		(13 "F.Paste" user "Package Geometry/Pastemask Top")
		(15 "B.Paste" user "Package Geometry/Pastemask Bottom")
		(5 "F.SilkS" user "Ref Des/Silkscreen Top")
		(7 "B.SilkS" user "Ref Des/Silkscreen Bottom")
		(1 "F.Mask" user "Board Geometry/Soldermask Top")
		(3 "B.Mask" user "Board Geometry/Soldermask Bottom")
		(17 "Dwgs.User" user "User.Drawings")
		(19 "Cmts.User" user "User.Comments")
		(21 "Eco1.User" user "User.Eco1")
		(23 "Eco2.User" user "User.Eco2")
		(25 "Edge.Cuts" user "Board Geometry/Outline")
		(27 "Margin" user)
		(31 "F.CrtYd" user "Package Geometry/Place Bound Top")
		(29 "B.CrtYd" user "Package Geometry/Place Bound Bottom")
		(35 "F.Fab" user "Ref Des/Assembly Top")
		(33 "B.Fab" user "Ref Des/Assembly Bottom")
	)
	(footprint ""
		(layer "F.Cu")
		(at 85.627718 -402.371052 -90)
		(property "Reference" "C735"
			(at 0 0 270)
			(layer "F.SilkS")
			(hide yes)
			(effects
				(font
					(size 1.27 1.27)
				)
			)
		)
		(property "Value" ""
			(at 0 0 270)
			(layer "F.Fab")
			(effects
				(font
					(size 1.27 1.27)
				)
			)
		)
		(duplicate_pad_numbers_are_jumpers no)
		(fp_line
			(start -0.299974 0.150114)
			(end -0.299974 -0.150114)
			(stroke
				(width 0.1)
				(type default)
			)
			(layer "F.Fab")
		)
		(fp_line
			(start 0.299974 0.150114)
			(end -0.299974 0.150114)
			(stroke
				(width 0.1)
				(type default)
			)
			(layer "F.Fab")
		)
		(fp_line
			(start -0.299974 -0.150114)
			(end 0.299974 -0.150114)
			(stroke
				(width 0.1)
				(type default)
			)
			(layer "F.Fab")
		)
		(fp_line
			(start 0.299974 -0.150114)
			(end 0.299974 0.150114)
			(stroke
				(width 0.1)
				(type default)
			)
			(layer "F.Fab")
		)
		(pad "1" smd rect
			(at -0.2667 0 270)
			(size 0.3048 0.381)
			(layers "F.Cu" "F.Mask" "F.Paste")
			(net "P5E_CPU1_PE0_TX_C_DP<3>")
		)
		(pad "2" smd rect
			(at 0.2667 0 270)
			(size 0.3048 0.381)
			(layers "F.Cu" "F.Mask" "F.Paste")
			(net "P5E_CPU1_PE0_TX_DP<3>")
		)
	)
	(footprint ""
		(layer "F.Cu")
		(at 122.61088 -92.674948 90)
		(property "Reference" "R241"
			(at 0 0 90)
			(layer "F.SilkS")
			(hide yes)
			(effects
				(font
					(size 1.27 1.27)
				)
			)
		)
		(property "Value" ""
			(at 0 0 90)
			(layer "F.Fab")
			(effects
				(font
					(size 1.27 1.27)
				)
			)
		)
		(duplicate_pad_numbers_are_jumpers no)
		(fp_line
			(start 0.7874 -0.4064)
			(end 0.7874 0.4064)
			(stroke
				(width 0.1524)
				(type default)
			)
			(layer "F.SilkS")
		)
		(fp_line
			(start -0.7874 -0.4064)
			(end 0.7874 -0.4064)
			(stroke
				(width 0.1524)
				(type default)
			)
			(layer "F.SilkS")
		)
		(fp_line
			(start 0.7874 0.4064)
			(end -0.7874 0.4064)
			(stroke
				(width 0.1524)
				(type default)
			)
			(layer "F.SilkS")
		)
		(fp_line
			(start -0.7874 0.4064)
			(end -0.7874 -0.4064)
			(stroke
				(width 0.1524)
				(type default)
			)
			(layer "F.SilkS")
		)
		(fp_line
			(start -0.12065 -0.305054)
			(end -0.12065 -0.2794)
			(stroke
				(width 0.1)
				(type default)
			)
			(layer "F.Fab")
		)
		(fp_line
			(start -0.67945 -0.305054)
			(end -0.12065 -0.305054)
			(stroke
				(width 0.1)
				(type default)
			)
			(layer "F.Fab")
		)
		(fp_line
			(start 0.67945 -0.3048)
			(end 0.67945 0.3048)
			(stroke
				(width 0.1)
				(type default)
			)
			(layer "F.Fab")
		)
		(fp_line
			(start 0.12065 -0.3048)
			(end 0.67945 -0.3048)
			(stroke
				(width 0.1)
				(type default)
			)
			(layer "F.Fab")
		)
		(fp_line
			(start 0.12065 -0.2794)
			(end 0.12065 -0.3048)
			(stroke
				(width 0.1)
				(type default)
			)
			(layer "F.Fab")
		)
		(fp_line
			(start -0.12065 -0.2794)
			(end 0.12065 -0.2794)
			(stroke
				(width 0.1)
				(type default)
			)
			(layer "F.Fab")
		)
		(fp_line
			(start 0.120396 0.2794)
			(end -0.12065 0.2794)
			(stroke
				(width 0.1)
				(type default)
			)
			(layer "F.Fab")
		)
		(fp_line
			(start -0.12065 0.2794)
			(end -0.12065 0.3048)
			(stroke
				(width 0.1)
				(type default)
			)
			(layer "F.Fab")
		)
		(fp_line
			(start 0.67945 0.3048)
			(end 0.120396 0.3048)
			(stroke
				(width 0.1)
				(type default)
			)
			(layer "F.Fab")
		)
		(fp_line
			(start 0.120396 0.3048)
			(end 0.120396 0.2794)
			(stroke
				(width 0.1)
				(type default)
			)
			(layer "F.Fab")
		)
		(fp_line
			(start -0.12065 0.3048)
			(end -0.67945 0.3048)
			(stroke
				(width 0.1)
				(type default)
			)
			(layer "F.Fab")
		)
		(fp_line
			(start -0.67945 0.3048)
			(end -0.67945 -0.305054)
			(stroke
				(width 0.1)
				(type default)
			)
			(layer "F.Fab")
		)
		(pad "1" smd circle
			(at -0.40005 0 90)
			(size 0 0)
			(layers "F.Cu" "F.Mask" "F.Paste")
			(net "P3V3")
		)
		(pad "2" smd circle
			(at 0.40005 0 90)
			(size 0 0)
			(layers "F.Cu" "F.Mask" "F.Paste")
			(net "H_CPU0_THERMTRIP_VT_N")
		)
	)
	(footprint ""
		(layer "F.Cu")
		(at 201.02068 -99.939348)
		(property "Reference" "R4294"
			(at 0 0 0)
			(layer "F.SilkS")
			(hide yes)
			(effects
				(font
					(size 1.27 1.27)
				)
			)
		)
		(property "Value" ""
			(at 0 0 0)
			(layer "F.Fab")
			(effects
				(font
					(size 1.27 1.27)
				)
			)
		)
		(duplicate_pad_numbers_are_jumpers no)
		(fp_line
			(start -0.7874 -0.4064)
			(end 0.7874 -0.4064)
			(stroke
				(width 0.1524)
				(type default)
			)
			(layer "F.SilkS")
		)
		(fp_line
			(start -0.7874 0.4064)
			(end -0.7874 -0.4064)
			(stroke
				(width 0.1524)
				(type default)
			)
			(layer "F.SilkS")
		)
		(fp_line
			(start 0.7874 -0.4064)
			(end 0.7874 0.4064)
			(stroke
				(width 0.1524)
				(type default)
			)
			(layer "F.SilkS")
		)
		(fp_line
			(start 0.7874 0.4064)
			(end -0.7874 0.4064)
			(stroke
				(width 0.1524)
				(type default)
			)
			(layer "F.SilkS")
		)
		(fp_line
			(start -0.67945 -0.305054)
			(end -0.12065 -0.305054)
			(stroke
				(width 0.1)
				(type default)
			)
			(layer "F.Fab")
		)
		(fp_line
			(start -0.67945 0.3048)
			(end -0.67945 -0.305054)
			(stroke
				(width 0.1)
				(type default)
			)
			(layer "F.Fab")
		)
		(fp_line
			(start -0.12065 -0.305054)
			(end -0.12065 -0.2794)
			(stroke
				(width 0.1)
				(type default)
			)
			(layer "F.Fab")
		)
		(fp_line
			(start -0.12065 -0.2794)
			(end 0.12065 -0.2794)
			(stroke
				(width 0.1)
				(type default)
			)
			(layer "F.Fab")
		)
		(fp_line
			(start -0.12065 0.2794)
			(end -0.12065 0.3048)
			(stroke
				(width 0.1)
				(type default)
			)
			(layer "F.Fab")
		)
		(fp_line
			(start -0.12065 0.3048)
			(end -0.67945 0.3048)
			(stroke
				(width 0.1)
				(type default)
			)
			(layer "F.Fab")
		)
		(fp_line
			(start 0.120396 0.2794)
			(end -0.12065 0.2794)
			(stroke
				(width 0.1)
				(type default)
			)
			(layer "F.Fab")
		)
		(fp_line
			(start 0.120396 0.3048)
			(end 0.120396 0.2794)
			(stroke
				(width 0.1)
				(type default)
			)
			(layer "F.Fab")
		)
		(fp_line
			(start 0.12065 -0.3048)
			(end 0.67945 -0.3048)
			(stroke
				(width 0.1)
				(type default)
			)
			(layer "F.Fab")
		)
		(fp_line
			(start 0.12065 -0.2794)
			(end 0.12065 -0.3048)
			(stroke
				(width 0.1)
				(type default)
			)
			(layer "F.Fab")
		)
		(fp_line
			(start 0.67945 -0.3048)
			(end 0.67945 0.3048)
			(stroke
				(width 0.1)
				(type default)
			)
			(layer "F.Fab")
		)
		(fp_line
			(start 0.67945 0.3048)
			(end 0.120396 0.3048)
			(stroke
				(width 0.1)
				(type default)
			)
			(layer "F.Fab")
		)
		(pad "1" smd circle
			(at -0.40005 0)
			(size 0 0)
			(layers "F.Cu" "F.Mask" "F.Paste")
			(net "H_CPU1_MEMHOT_IN_LVC1_R1_N")
		)
		(pad "2" smd circle
			(at 0.40005 0)
			(size 0 0)
			(layers "F.Cu" "F.Mask" "F.Paste")
			(net "H_CPU1_MEMHOT_IN_LVC1_N")
		)
	)
	(footprint ""
		(layer "F.Cu")
		(at 317.396622 -59.299348 180)
		(property "Reference" "R1221"
			(at 0 0 180)
			(layer "F.SilkS")
			(hide yes)
			(effects
				(font
					(size 1.27 1.27)
				)
			)
		)
		(property "Value" ""
			(at 0 0 180)
			(layer "F.Fab")
			(effects
				(font
					(size 1.27 1.27)
				)
			)
		)
		(duplicate_pad_numbers_are_jumpers no)
		(fp_line
			(start 0.7874 0.4064)
			(end -0.7874 0.4064)
			(stroke
				(width 0.1524)
				(type default)
			)
			(layer "F.SilkS")
		)
		(fp_line
			(start 0.7874 -0.4064)
			(end 0.7874 0.4064)
			(stroke
				(width 0.1524)
				(type default)
			)
			(layer "F.SilkS")
		)
		(fp_line
			(start -0.7874 0.4064)
			(end -0.7874 -0.4064)
			(stroke
				(width 0.1524)
				(type default)
			)
			(layer "F.SilkS")
		)
		(fp_line
			(start -0.7874 -0.4064)
			(end 0.7874 -0.4064)
			(stroke
				(width 0.1524)
				(type default)
			)
			(layer "F.SilkS")
		)
		(fp_line
			(start 0.67945 0.3048)
			(end 0.120396 0.3048)
			(stroke
				(width 0.1)
				(type default)
			)
			(layer "F.Fab")
		)
		(fp_line
			(start 0.67945 -0.3048)
			(end 0.67945 0.3048)
			(stroke
				(width 0.1)
				(type default)
			)
			(layer "F.Fab")
		)
		(fp_line
			(start 0.12065 -0.2794)
			(end 0.12065 -0.3048)
			(stroke
				(width 0.1)
				(type default)
			)
			(layer "F.Fab")
		)
		(fp_line
			(start 0.12065 -0.3048)
			(end 0.67945 -0.3048)
			(stroke
				(width 0.1)
				(type default)
			)
			(layer "F.Fab")
		)
		(fp_line
			(start 0.120396 0.3048)
			(end 0.120396 0.2794)
			(stroke
				(width 0.1)
				(type default)
			)
			(layer "F.Fab")
		)
		(fp_line
			(start 0.120396 0.2794)
			(end -0.12065 0.2794)
			(stroke
				(width 0.1)
				(type default)
			)
			(layer "F.Fab")
		)
		(fp_line
			(start -0.12065 0.3048)
			(end -0.67945 0.3048)
			(stroke
				(width 0.1)
				(type default)
			)
			(layer "F.Fab")
		)
		(fp_line
			(start -0.12065 0.2794)
			(end -0.12065 0.3048)
			(stroke
				(width 0.1)
				(type default)
			)
			(layer "F.Fab")
		)
		(fp_line
			(start -0.12065 -0.2794)
			(end 0.12065 -0.2794)
			(stroke
				(width 0.1)
				(type default)
			)
			(layer "F.Fab")
		)
		(fp_line
			(start -0.12065 -0.305054)
			(end -0.12065 -0.2794)
			(stroke
				(width 0.1)
				(type default)
			)
			(layer "F.Fab")
		)
		(fp_line
			(start -0.67945 0.3048)
			(end -0.67945 -0.305054)
			(stroke
				(width 0.1)
				(type default)
			)
			(layer "F.Fab")
		)
		(fp_line
			(start -0.67945 -0.305054)
			(end -0.12065 -0.305054)
			(stroke
				(width 0.1)
				(type default)
			)
			(layer "F.Fab")
		)
		(pad "1" smd circle
			(at -0.40005 0 180)
			(size 0 0)
			(layers "F.Cu" "F.Mask" "F.Paste")
			(net "FM_PCH_MCRO_LDO")
		)
		(pad "2" smd circle
			(at 0.40005 0 180)
			(size 0 0)
			(layers "F.Cu" "F.Mask" "F.Paste")
			(net "GND")
		)
	)
	(footprint ""
		(layer "F.Cu")
		(at 205.397608 -402.791422 180)
		(property "Reference" "PR1101"
			(at 0 0 180)
			(layer "F.SilkS")
			(hide yes)
			(effects
				(font
					(size 1.27 1.27)
				)
			)
		)
		(property "Value" ""
			(at 0 0 180)
			(layer "F.Fab")
			(effects
				(font
					(size 1.27 1.27)
				)
			)
		)
		(duplicate_pad_numbers_are_jumpers no)
		(fp_line
			(start 0.7874 0.4064)
			(end -0.7874 0.4064)
			(stroke
				(width 0.1524)
				(type default)
			)
			(layer "F.SilkS")
		)
		(fp_line
			(start 0.7874 -0.4064)
			(end 0.7874 0.4064)
			(stroke
				(width 0.1524)
				(type default)
			)
			(layer "F.SilkS")
		)
		(fp_line
			(start -0.7874 0.4064)
			(end -0.7874 -0.4064)
			(stroke
				(width 0.1524)
				(type default)
			)
			(layer "F.SilkS")
		)
		(fp_line
			(start -0.7874 -0.4064)
			(end 0.7874 -0.4064)
			(stroke
				(width 0.1524)
				(type default)
			)
			(layer "F.SilkS")
		)
		(fp_line
			(start 0.67945 0.3048)
			(end 0.120396 0.3048)
			(stroke
				(width 0.1)
				(type default)
			)
			(layer "F.Fab")
		)
		(fp_line
			(start 0.67945 -0.3048)
			(end 0.67945 0.3048)
			(stroke
				(width 0.1)
				(type default)
			)
			(layer "F.Fab")
		)
		(fp_line
			(start 0.12065 -0.2794)
			(end 0.12065 -0.3048)
			(stroke
				(width 0.1)
				(type default)
			)
			(layer "F.Fab")
		)
		(fp_line
			(start 0.12065 -0.3048)
			(end 0.67945 -0.3048)
			(stroke
				(width 0.1)
				(type default)
			)
			(layer "F.Fab")
		)
		(fp_line
			(start 0.120396 0.3048)
			(end 0.120396 0.2794)
			(stroke
				(width 0.1)
				(type default)
			)
			(layer "F.Fab")
		)
		(fp_line
			(start 0.120396 0.2794)
			(end -0.12065 0.2794)
			(stroke
				(width 0.1)
				(type default)
			)
			(layer "F.Fab")
		)
		(fp_line
			(start -0.12065 0.3048)
			(end -0.67945 0.3048)
			(stroke
				(width 0.1)
				(type default)
			)
			(layer "F.Fab")
		)
		(fp_line
			(start -0.12065 0.2794)
			(end -0.12065 0.3048)
			(stroke
				(width 0.1)
				(type default)
			)
			(layer "F.Fab")
		)
		(fp_line
			(start -0.12065 -0.2794)
			(end 0.12065 -0.2794)
			(stroke
				(width 0.1)
				(type default)
			)
			(layer "F.Fab")
		)
		(fp_line
			(start -0.12065 -0.305054)
			(end -0.12065 -0.2794)
			(stroke
				(width 0.1)
				(type default)
			)
			(layer "F.Fab")
		)
		(fp_line
			(start -0.67945 0.3048)
			(end -0.67945 -0.305054)
			(stroke
				(width 0.1)
				(type default)
			)
			(layer "F.Fab")
		)
		(fp_line
			(start -0.67945 -0.305054)
			(end -0.12065 -0.305054)
			(stroke
				(width 0.1)
				(type default)
			)
			(layer "F.Fab")
		)
		(pad "1" smd circle
			(at -0.40005 0 180)
			(size 0 0)
			(layers "F.Cu" "F.Mask" "F.Paste")
			(net "HSC_IMON")
		)
		(pad "2" smd circle
			(at 0.40005 0 180)
			(size 0 0)
			(layers "F.Cu" "F.Mask" "F.Paste")
			(net "AGND_HSC")
		)
	)
	(footprint ""
		(layer "F.Cu")
		(at 307.932328 -402.371052 -90)
		(property "Reference" "C1576"
			(at 0 0 270)
			(layer "F.SilkS")
			(hide yes)
			(effects
				(font
					(size 1.27 1.27)
				)
			)
		)
		(property "Value" ""
			(at 0 0 270)
			(layer "F.Fab")
			(effects
				(font
					(size 1.27 1.27)
				)
			)
		)
		(duplicate_pad_numbers_are_jumpers no)
		(fp_line
			(start -0.299974 0.150114)
			(end -0.299974 -0.150114)
			(stroke
				(width 0.1)
				(type default)
			)
			(layer "F.Fab")
		)
		(fp_line
			(start 0.299974 0.150114)
			(end -0.299974 0.150114)
			(stroke
				(width 0.1)
				(type default)
			)
			(layer "F.Fab")
		)
		(fp_line
			(start -0.299974 -0.150114)
			(end 0.299974 -0.150114)
			(stroke
				(width 0.1)
				(type default)
			)
			(layer "F.Fab")
		)
		(fp_line
			(start 0.299974 -0.150114)
			(end 0.299974 0.150114)
			(stroke
				(width 0.1)
				(type default)
			)
			(layer "F.Fab")
		)
		(pad "1" smd rect
			(at -0.2667 0 270)
			(size 0.3048 0.381)
			(layers "F.Cu" "F.Mask" "F.Paste")
			(net "P5E_CPU0_PE4_TX_C_DN<1>")
		)
		(pad "2" smd rect
			(at 0.2667 0 270)
			(size 0.3048 0.381)
			(layers "F.Cu" "F.Mask" "F.Paste")
			(net "P5E_CPU0_PE4_TX_DN<1>")
		)
	)
	(footprint ""
		(layer "F.Cu")
		(at 96.57588 -54.066948 180)
		(property "Reference" "R1375"
			(at 0 0 180)
			(layer "F.SilkS")
			(hide yes)
			(effects
				(font
					(size 1.27 1.27)
				)
			)
		)
		(property "Value" ""
			(at 0 0 180)
			(layer "F.Fab")
			(effects
				(font
					(size 1.27 1.27)
				)
			)
		)
		(duplicate_pad_numbers_are_jumpers no)
		(fp_line
			(start 0.7874 0.4064)
			(end -0.7874 0.4064)
			(stroke
				(width 0.1524)
				(type default)
			)
			(layer "F.SilkS")
		)
		(fp_line
			(start 0.7874 -0.4064)
			(end 0.7874 0.4064)
			(stroke
				(width 0.1524)
				(type default)
			)
			(layer "F.SilkS")
		)
		(fp_line
			(start -0.7874 0.4064)
			(end -0.7874 -0.4064)
			(stroke
				(width 0.1524)
				(type default)
			)
			(layer "F.SilkS")
		)
		(fp_line
			(start -0.7874 -0.4064)
			(end 0.7874 -0.4064)
			(stroke
				(width 0.1524)
				(type default)
			)
			(layer "F.SilkS")
		)
		(fp_line
			(start 0.67945 0.3048)
			(end 0.120396 0.3048)
			(stroke
				(width 0.1)
				(type default)
			)
			(layer "F.Fab")
		)
		(fp_line
			(start 0.67945 -0.3048)
			(end 0.67945 0.3048)
			(stroke
				(width 0.1)
				(type default)
			)
			(layer "F.Fab")
		)
		(fp_line
			(start 0.12065 -0.2794)
			(end 0.12065 -0.3048)
			(stroke
				(width 0.1)
				(type default)
			)
			(layer "F.Fab")
		)
		(fp_line
			(start 0.12065 -0.3048)
			(end 0.67945 -0.3048)
			(stroke
				(width 0.1)
				(type default)
			)
			(layer "F.Fab")
		)
		(fp_line
			(start 0.120396 0.3048)
			(end 0.120396 0.2794)
			(stroke
				(width 0.1)
				(type default)
			)
			(layer "F.Fab")
		)
		(fp_line
			(start 0.120396 0.2794)
			(end -0.12065 0.2794)
			(stroke
				(width 0.1)
				(type default)
			)
			(layer "F.Fab")
		)
		(fp_line
			(start -0.12065 0.3048)
			(end -0.67945 0.3048)
			(stroke
				(width 0.1)
				(type default)
			)
			(layer "F.Fab")
		)
		(fp_line
			(start -0.12065 0.2794)
			(end -0.12065 0.3048)
			(stroke
				(width 0.1)
				(type default)
			)
			(layer "F.Fab")
		)
		(fp_line
			(start -0.12065 -0.2794)
			(end 0.12065 -0.2794)
			(stroke
				(width 0.1)
				(type default)
			)
			(layer "F.Fab")
		)
		(fp_line
			(start -0.12065 -0.305054)
			(end -0.12065 -0.2794)
			(stroke
				(width 0.1)
				(type default)
			)
			(layer "F.Fab")
		)
		(fp_line
			(start -0.67945 0.3048)
			(end -0.67945 -0.305054)
			(stroke
				(width 0.1)
				(type default)
			)
			(layer "F.Fab")
		)
		(fp_line
			(start -0.67945 -0.305054)
			(end -0.12065 -0.305054)
			(stroke
				(width 0.1)
				(type default)
			)
			(layer "F.Fab")
		)
		(pad "1" smd circle
			(at -0.40005 0 180)
			(size 0 0)
			(layers "F.Cu" "F.Mask" "F.Paste")
			(net "FM_BMC_EN_DET")
		)
		(pad "2" smd circle
			(at 0.40005 0 180)
			(size 0 0)
			(layers "F.Cu" "F.Mask" "F.Paste")
			(net "GND")
		)
	)
)
